(kicad_pcb
	(version 20260206)
	(generator "pcbnew")
	(generator_version "10.0")
	(general
		(thickness 1.6)
		(legacy_teardrops no)
	)
	(paper "A4")
	(title_block
		(title "03242023_DA0F0TMBIJ0_F0T_Motherboard_J_brd_V01_OCP.brd")
		(comment 1 "Grand Teton / footprints 2326-2332 of 6105")
	)
	(layers
		(0 "F.Cu" signal "TOP")
		(4 "In1.Cu" signal "GND")
		(6 "In2.Cu" signal "IN1")
		(8 "In3.Cu" signal "GND1")
		(10 "In4.Cu" signal "IN2")
		(12 "In5.Cu" signal "GND2")
		(14 "In6.Cu" signal "IN3")
		(16 "In7.Cu" signal "GND3")
		(18 "In8.Cu" signal "VCC")
		(20 "In9.Cu" signal "VCC1")
		(22 "In10.Cu" signal "GND4")
		(24 "In11.Cu" signal "IN4")
		(26 "In12.Cu" signal "GND5")
		(28 "In13.Cu" signal "IN5")
		(30 "In14.Cu" signal "GND6")
		(32 "In15.Cu" signal "IN6")
		(34 "In16.Cu" signal "GND7")
		(2 "B.Cu" signal "BOTTOM")
		(9 "F.Adhes" user "F.Adhesive")
		(11 "B.Adhes" user "B.Adhesive")
		(13 "F.Paste" user "Package Geometry/Pastemask Top")
		(15 "B.Paste" user "Package Geometry/Pastemask Bottom")
		(5 "F.SilkS" user "Ref Des/Silkscreen Top")
		(7 "B.SilkS" user "Ref Des/Silkscreen Bottom")
		(1 "F.Mask" user "Board Geometry/Soldermask Top")
		(3 "B.Mask" user "Board Geometry/Soldermask Bottom")
		(17 "Dwgs.User" user "User.Drawings")
		(19 "Cmts.User" user "User.Comments")
		(21 "Eco1.User" user "User.Eco1")
		(23 "Eco2.User" user "User.Eco2")
		(25 "Edge.Cuts" user "Board Geometry/Outline")
		(27 "Margin" user)
		(31 "F.CrtYd" user "Package Geometry/Place Bound Top")
		(29 "B.CrtYd" user "Package Geometry/Place Bound Bottom")
		(35 "F.Fab" user "Ref Des/Assembly Top")
		(33 "B.Fab" user "Ref Des/Assembly Bottom")
	)
	(footprint ""
		(layer "F.Cu")
		(at 458.799946 -435.600094)
		(property "Reference" "H87"
			(at -5.13588 -4.694428 0)
			(unlocked yes)
			(layer "F.SilkS")
			(effects
				(font
					(size 0.7874 0.5842)
					(thickness 0.1524)
				)
				(justify left)
			)
		)
		(property "Value" ""
			(at 0 0 0)
			(layer "F.Fab")
			(effects
				(font
					(size 1.27 1.27)
				)
			)
		)
		(duplicate_pad_numbers_are_jumpers no)
		(pad "1" thru_hole circle
			(at 0 0)
			(size 10.0076 10.0076)
			(drill 5.6134)
			(layers "*.Cu" "*.Mask")
			(remove_unused_layers no)
			(net "GND")
			(clearance -1.9431)
		)
	)
	(footprint ""
		(layer "F.Cu")
		(at 140.00988 -40.985948 180)
		(property "Reference" "R2121"
			(at 0 0 180)
			(layer "F.SilkS")
			(hide yes)
			(effects
				(font
					(size 1.27 1.27)
				)
			)
		)
		(property "Value" ""
			(at 0 0 180)
			(layer "F.Fab")
			(effects
				(font
					(size 1.27 1.27)
				)
			)
		)
		(duplicate_pad_numbers_are_jumpers no)
		(fp_line
			(start 0.7874 0.4064)
			(end -0.7874 0.4064)
			(stroke
				(width 0.1524)
				(type default)
			)
			(layer "F.SilkS")
		)
		(fp_line
			(start 0.7874 -0.4064)
			(end 0.7874 0.4064)
			(stroke
				(width 0.1524)
				(type default)
			)
			(layer "F.SilkS")
		)
		(fp_line
			(start -0.7874 0.4064)
			(end -0.7874 -0.4064)
			(stroke
				(width 0.1524)
				(type default)
			)
			(layer "F.SilkS")
		)
		(fp_line
			(start -0.7874 -0.4064)
			(end 0.7874 -0.4064)
			(stroke
				(width 0.1524)
				(type default)
			)
			(layer "F.SilkS")
		)
		(fp_line
			(start 0.67945 0.3048)
			(end 0.120396 0.3048)
			(stroke
				(width 0.1)
				(type default)
			)
			(layer "F.Fab")
		)
		(fp_line
			(start 0.67945 -0.3048)
			(end 0.67945 0.3048)
			(stroke
				(width 0.1)
				(type default)
			)
			(layer "F.Fab")
		)
		(fp_line
			(start 0.12065 -0.2794)
			(end 0.12065 -0.3048)
			(stroke
				(width 0.1)
				(type default)
			)
			(layer "F.Fab")
		)
		(fp_line
			(start 0.12065 -0.3048)
			(end 0.67945 -0.3048)
			(stroke
				(width 0.1)
				(type default)
			)
			(layer "F.Fab")
		)
		(fp_line
			(start 0.120396 0.3048)
			(end 0.120396 0.2794)
			(stroke
				(width 0.1)
				(type default)
			)
			(layer "F.Fab")
		)
		(fp_line
			(start 0.120396 0.2794)
			(end -0.12065 0.2794)
			(stroke
				(width 0.1)
				(type default)
			)
			(layer "F.Fab")
		)
		(fp_line
			(start -0.12065 0.3048)
			(end -0.67945 0.3048)
			(stroke
				(width 0.1)
				(type default)
			)
			(layer "F.Fab")
		)
		(fp_line
			(start -0.12065 0.2794)
			(end -0.12065 0.3048)
			(stroke
				(width 0.1)
				(type default)
			)
			(layer "F.Fab")
		)
		(fp_line
			(start -0.12065 -0.2794)
			(end 0.12065 -0.2794)
			(stroke
				(width 0.1)
				(type default)
			)
			(layer "F.Fab")
		)
		(fp_line
			(start -0.12065 -0.305054)
			(end -0.12065 -0.2794)
			(stroke
				(width 0.1)
				(type default)
			)
			(layer "F.Fab")
		)
		(fp_line
			(start -0.67945 0.3048)
			(end -0.67945 -0.305054)
			(stroke
				(width 0.1)
				(type default)
			)
			(layer "F.Fab")
		)
		(fp_line
			(start -0.67945 -0.305054)
			(end -0.12065 -0.305054)
			(stroke
				(width 0.1)
				(type default)
			)
			(layer "F.Fab")
		)
		(pad "1" smd circle
			(at -0.40005 0 180)
			(size 0 0)
			(layers "F.Cu" "F.Mask" "F.Paste")
			(net "P3V3_AUX")
		)
		(pad "2" smd circle
			(at 0.40005 0 180)
			(size 0 0)
			(layers "F.Cu" "F.Mask" "F.Paste")
			(net "RST_PCIE_PCH_DEV_BUF_M2_0_PERST")
		)
	)
	(footprint ""
		(layer "F.Cu")
		(at 24.069802 -410.418534)
		(property "Reference" "R3504"
			(at 0 0 0)
			(layer "F.SilkS")
			(hide yes)
			(effects
				(font
					(size 1.27 1.27)
				)
			)
		)
		(property "Value" ""
			(at 0 0 0)
			(layer "F.Fab")
			(effects
				(font
					(size 1.27 1.27)
				)
			)
		)
		(duplicate_pad_numbers_are_jumpers no)
		(fp_line
			(start -0.7874 -0.4064)
			(end 0.7874 -0.4064)
			(stroke
				(width 0.1524)
				(type default)
			)
			(layer "F.SilkS")
		)
		(fp_line
			(start -0.7874 0.4064)
			(end -0.7874 -0.4064)
			(stroke
				(width 0.1524)
				(type default)
			)
			(layer "F.SilkS")
		)
		(fp_line
			(start 0.7874 -0.4064)
			(end 0.7874 0.4064)
			(stroke
				(width 0.1524)
				(type default)
			)
			(layer "F.SilkS")
		)
		(fp_line
			(start 0.7874 0.4064)
			(end -0.7874 0.4064)
			(stroke
				(width 0.1524)
				(type default)
			)
			(layer "F.SilkS")
		)
		(fp_line
			(start -0.67945 -0.305054)
			(end -0.12065 -0.305054)
			(stroke
				(width 0.1)
				(type default)
			)
			(layer "F.Fab")
		)
		(fp_line
			(start -0.67945 0.3048)
			(end -0.67945 -0.305054)
			(stroke
				(width 0.1)
				(type default)
			)
			(layer "F.Fab")
		)
		(fp_line
			(start -0.12065 -0.305054)
			(end -0.12065 -0.2794)
			(stroke
				(width 0.1)
				(type default)
			)
			(layer "F.Fab")
		)
		(fp_line
			(start -0.12065 -0.2794)
			(end 0.12065 -0.2794)
			(stroke
				(width 0.1)
				(type default)
			)
			(layer "F.Fab")
		)
		(fp_line
			(start -0.12065 0.2794)
			(end -0.12065 0.3048)
			(stroke
				(width 0.1)
				(type default)
			)
			(layer "F.Fab")
		)
		(fp_line
			(start -0.12065 0.3048)
			(end -0.67945 0.3048)
			(stroke
				(width 0.1)
				(type default)
			)
			(layer "F.Fab")
		)
		(fp_line
			(start 0.120396 0.2794)
			(end -0.12065 0.2794)
			(stroke
				(width 0.1)
				(type default)
			)
			(layer "F.Fab")
		)
		(fp_line
			(start 0.120396 0.3048)
			(end 0.120396 0.2794)
			(stroke
				(width 0.1)
				(type default)
			)
			(layer "F.Fab")
		)
		(fp_line
			(start 0.12065 -0.3048)
			(end 0.67945 -0.3048)
			(stroke
				(width 0.1)
				(type default)
			)
			(layer "F.Fab")
		)
		(fp_line
			(start 0.12065 -0.2794)
			(end 0.12065 -0.3048)
			(stroke
				(width 0.1)
				(type default)
			)
			(layer "F.Fab")
		)
		(fp_line
			(start 0.67945 -0.3048)
			(end 0.67945 0.3048)
			(stroke
				(width 0.1)
				(type default)
			)
			(layer "F.Fab")
		)
		(fp_line
			(start 0.67945 0.3048)
			(end 0.120396 0.3048)
			(stroke
				(width 0.1)
				(type default)
			)
			(layer "F.Fab")
		)
		(pad "1" smd circle
			(at -0.40005 0)
			(size 0 0)
			(layers "F.Cu" "F.Mask" "F.Paste")
			(net "P3V3_AUX")
		)
		(pad "2" smd circle
			(at 0.40005 0)
			(size 0 0)
			(layers "F.Cu" "F.Mask" "F.Paste")
			(net "GPU_FPGA_EROT_FATALERR_ISO_N")
		)
	)
	(footprint ""
		(layer "F.Cu")
		(at 40.273732 -358.691942)
		(property "Reference" "PR1304"
			(at 0 0 0)
			(layer "F.SilkS")
			(hide yes)
			(effects
				(font
					(size 1.27 1.27)
				)
			)
		)
		(property "Value" ""
			(at 0 0 0)
			(layer "F.Fab")
			(effects
				(font
					(size 1.27 1.27)
				)
			)
		)
		(duplicate_pad_numbers_are_jumpers no)
		(fp_line
			(start -0.7874 -0.4064)
			(end 0.7874 -0.4064)
			(stroke
				(width 0.1524)
				(type default)
			)
			(layer "F.SilkS")
		)
		(fp_line
			(start -0.7874 0.4064)
			(end -0.7874 -0.4064)
			(stroke
				(width 0.1524)
				(type default)
			)
			(layer "F.SilkS")
		)
		(fp_line
			(start 0.7874 -0.4064)
			(end 0.7874 0.4064)
			(stroke
				(width 0.1524)
				(type default)
			)
			(layer "F.SilkS")
		)
		(fp_line
			(start 0.7874 0.4064)
			(end -0.7874 0.4064)
			(stroke
				(width 0.1524)
				(type default)
			)
			(layer "F.SilkS")
		)
		(fp_line
			(start -0.67945 -0.305054)
			(end -0.12065 -0.305054)
			(stroke
				(width 0.1)
				(type default)
			)
			(layer "F.Fab")
		)
		(fp_line
			(start -0.67945 0.3048)
			(end -0.67945 -0.305054)
			(stroke
				(width 0.1)
				(type default)
			)
			(layer "F.Fab")
		)
		(fp_line
			(start -0.12065 -0.305054)
			(end -0.12065 -0.2794)
			(stroke
				(width 0.1)
				(type default)
			)
			(layer "F.Fab")
		)
		(fp_line
			(start -0.12065 -0.2794)
			(end 0.12065 -0.2794)
			(stroke
				(width 0.1)
				(type default)
			)
			(layer "F.Fab")
		)
		(fp_line
			(start -0.12065 0.2794)
			(end -0.12065 0.3048)
			(stroke
				(width 0.1)
				(type default)
			)
			(layer "F.Fab")
		)
		(fp_line
			(start -0.12065 0.3048)
			(end -0.67945 0.3048)
			(stroke
				(width 0.1)
				(type default)
			)
			(layer "F.Fab")
		)
		(fp_line
			(start 0.120396 0.2794)
			(end -0.12065 0.2794)
			(stroke
				(width 0.1)
				(type default)
			)
			(layer "F.Fab")
		)
		(fp_line
			(start 0.120396 0.3048)
			(end 0.120396 0.2794)
			(stroke
				(width 0.1)
				(type default)
			)
			(layer "F.Fab")
		)
		(fp_line
			(start 0.12065 -0.3048)
			(end 0.67945 -0.3048)
			(stroke
				(width 0.1)
				(type default)
			)
			(layer "F.Fab")
		)
		(fp_line
			(start 0.12065 -0.2794)
			(end 0.12065 -0.3048)
			(stroke
				(width 0.1)
				(type default)
			)
			(layer "F.Fab")
		)
		(fp_line
			(start 0.67945 -0.3048)
			(end 0.67945 0.3048)
			(stroke
				(width 0.1)
				(type default)
			)
			(layer "F.Fab")
		)
		(fp_line
			(start 0.67945 0.3048)
			(end 0.120396 0.3048)
			(stroke
				(width 0.1)
				(type default)
			)
			(layer "F.Fab")
		)
		(pad "1" smd circle
			(at -0.40005 0)
			(size 0 0)
			(layers "F.Cu" "F.Mask" "F.Paste")
			(net "PVCCFA_EHV_FIVRA_CPU1_LSET4")
		)
		(pad "2" smd circle
			(at 0.40005 0)
			(size 0 0)
			(layers "F.Cu" "F.Mask" "F.Paste")
			(net "GND")
		)
	)
	(footprint ""
		(layer "F.Cu")
		(at 120.37822 -421.447468)
		(property "Reference" "R2925"
			(at 0 0 0)
			(layer "F.SilkS")
			(hide yes)
			(effects
				(font
					(size 1.27 1.27)
				)
			)
		)
		(property "Value" ""
			(at 0 0 0)
			(layer "F.Fab")
			(effects
				(font
					(size 1.27 1.27)
				)
			)
		)
		(duplicate_pad_numbers_are_jumpers no)
		(fp_line
			(start -0.7874 -0.4064)
			(end 0.7874 -0.4064)
			(stroke
				(width 0.1524)
				(type default)
			)
			(layer "F.SilkS")
		)
		(fp_line
			(start -0.7874 0.4064)
			(end -0.7874 -0.4064)
			(stroke
				(width 0.1524)
				(type default)
			)
			(layer "F.SilkS")
		)
		(fp_line
			(start 0.7874 -0.4064)
			(end 0.7874 0.4064)
			(stroke
				(width 0.1524)
				(type default)
			)
			(layer "F.SilkS")
		)
		(fp_line
			(start 0.7874 0.4064)
			(end -0.7874 0.4064)
			(stroke
				(width 0.1524)
				(type default)
			)
			(layer "F.SilkS")
		)
		(fp_line
			(start -0.67945 -0.305054)
			(end -0.12065 -0.305054)
			(stroke
				(width 0.1)
				(type default)
			)
			(layer "F.Fab")
		)
		(fp_line
			(start -0.67945 0.3048)
			(end -0.67945 -0.305054)
			(stroke
				(width 0.1)
				(type default)
			)
			(layer "F.Fab")
		)
		(fp_line
			(start -0.12065 -0.305054)
			(end -0.12065 -0.2794)
			(stroke
				(width 0.1)
				(type default)
			)
			(layer "F.Fab")
		)
		(fp_line
			(start -0.12065 -0.2794)
			(end 0.12065 -0.2794)
			(stroke
				(width 0.1)
				(type default)
			)
			(layer "F.Fab")
		)
		(fp_line
			(start -0.12065 0.2794)
			(end -0.12065 0.3048)
			(stroke
				(width 0.1)
				(type default)
			)
			(layer "F.Fab")
		)
		(fp_line
			(start -0.12065 0.3048)
			(end -0.67945 0.3048)
			(stroke
				(width 0.1)
				(type default)
			)
			(layer "F.Fab")
		)
		(fp_line
			(start 0.120396 0.2794)
			(end -0.12065 0.2794)
			(stroke
				(width 0.1)
				(type default)
			)
			(layer "F.Fab")
		)
		(fp_line
			(start 0.120396 0.3048)
			(end 0.120396 0.2794)
			(stroke
				(width 0.1)
				(type default)
			)
			(layer "F.Fab")
		)
		(fp_line
			(start 0.12065 -0.3048)
			(end 0.67945 -0.3048)
			(stroke
				(width 0.1)
				(type default)
			)
			(layer "F.Fab")
		)
		(fp_line
			(start 0.12065 -0.2794)
			(end 0.12065 -0.3048)
			(stroke
				(width 0.1)
				(type default)
			)
			(layer "F.Fab")
		)
		(fp_line
			(start 0.67945 -0.3048)
			(end 0.67945 0.3048)
			(stroke
				(width 0.1)
				(type default)
			)
			(layer "F.Fab")
		)
		(fp_line
			(start 0.67945 0.3048)
			(end 0.120396 0.3048)
			(stroke
				(width 0.1)
				(type default)
			)
			(layer "F.Fab")
		)
		(pad "1" smd circle
			(at -0.40005 0)
			(size 0 0)
			(layers "F.Cu" "F.Mask" "F.Paste")
			(net "FM_GPU_PWR_EN_R1")
		)
		(pad "2" smd circle
			(at 0.40005 0)
			(size 0 0)
			(layers "F.Cu" "F.Mask" "F.Paste")
			(net "FM_GPU_PWR_EN_R_BUF")
		)
	)
	(footprint ""
		(layer "F.Cu")
		(at 211.99729 -69.86143)
		(property "Reference" "R1355"
			(at 0 0 0)
			(layer "F.SilkS")
			(hide yes)
			(effects
				(font
					(size 1.27 1.27)
				)
			)
		)
		(property "Value" ""
			(at 0 0 0)
			(layer "F.Fab")
			(effects
				(font
					(size 1.27 1.27)
				)
			)
		)
		(duplicate_pad_numbers_are_jumpers no)
		(fp_line
			(start -0.7874 -0.4064)
			(end 0.7874 -0.4064)
			(stroke
				(width 0.1524)
				(type default)
			)
			(layer "F.SilkS")
		)
		(fp_line
			(start -0.7874 0.4064)
			(end -0.7874 -0.4064)
			(stroke
				(width 0.1524)
				(type default)
			)
			(layer "F.SilkS")
		)
		(fp_line
			(start 0.7874 -0.4064)
			(end 0.7874 0.4064)
			(stroke
				(width 0.1524)
				(type default)
			)
			(layer "F.SilkS")
		)
		(fp_line
			(start 0.7874 0.4064)
			(end -0.7874 0.4064)
			(stroke
				(width 0.1524)
				(type default)
			)
			(layer "F.SilkS")
		)
		(fp_line
			(start -0.67945 -0.305054)
			(end -0.12065 -0.305054)
			(stroke
				(width 0.1)
				(type default)
			)
			(layer "F.Fab")
		)
		(fp_line
			(start -0.67945 0.3048)
			(end -0.67945 -0.305054)
			(stroke
				(width 0.1)
				(type default)
			)
			(layer "F.Fab")
		)
		(fp_line
			(start -0.12065 -0.305054)
			(end -0.12065 -0.2794)
			(stroke
				(width 0.1)
				(type default)
			)
			(layer "F.Fab")
		)
		(fp_line
			(start -0.12065 -0.2794)
			(end 0.12065 -0.2794)
			(stroke
				(width 0.1)
				(type default)
			)
			(layer "F.Fab")
		)
		(fp_line
			(start -0.12065 0.2794)
			(end -0.12065 0.3048)
			(stroke
				(width 0.1)
				(type default)
			)
			(layer "F.Fab")
		)
		(fp_line
			(start -0.12065 0.3048)
			(end -0.67945 0.3048)
			(stroke
				(width 0.1)
				(type default)
			)
			(layer "F.Fab")
		)
		(fp_line
			(start 0.120396 0.2794)
			(end -0.12065 0.2794)
			(stroke
				(width 0.1)
				(type default)
			)
			(layer "F.Fab")
		)
		(fp_line
			(start 0.120396 0.3048)
			(end 0.120396 0.2794)
			(stroke
				(width 0.1)
				(type default)
			)
			(layer "F.Fab")
		)
		(fp_line
			(start 0.12065 -0.3048)
			(end 0.67945 -0.3048)
			(stroke
				(width 0.1)
				(type default)
			)
			(layer "F.Fab")
		)
		(fp_line
			(start 0.12065 -0.2794)
			(end 0.12065 -0.3048)
			(stroke
				(width 0.1)
				(type default)
			)
			(layer "F.Fab")
		)
		(fp_line
			(start 0.67945 -0.3048)
			(end 0.67945 0.3048)
			(stroke
				(width 0.1)
				(type default)
			)
			(layer "F.Fab")
		)
		(fp_line
			(start 0.67945 0.3048)
			(end 0.120396 0.3048)
			(stroke
				(width 0.1)
				(type default)
			)
			(layer "F.Fab")
		)
		(pad "1" smd circle
			(at -0.40005 0)
			(size 0 0)
			(layers "F.Cu" "F.Mask" "F.Paste")
			(net "RMII_BMC_OCP_TXD_1")
		)
		(pad "2" smd circle
			(at 0.40005 0)
			(size 0 0)
			(layers "F.Cu" "F.Mask" "F.Paste")
			(net "GND")
		)
	)
	(footprint ""
		(layer "F.Cu")
		(at 175.31588 -130.266948 90)
		(property "Reference" "C1211"
			(at 0 0 90)
			(layer "F.SilkS")
			(hide yes)
			(effects
				(font
					(size 1.27 1.27)
				)
			)
		)
		(property "Value" ""
			(at 0 0 90)
			(layer "F.Fab")
			(effects
				(font
					(size 1.27 1.27)
				)
			)
		)
		(duplicate_pad_numbers_are_jumpers no)
		(fp_line
			(start 0.7874 -0.4064)
			(end 0.7874 0.4064)
			(stroke
				(width 0.1524)
				(type default)
			)
			(layer "F.SilkS")
		)
		(fp_line
			(start -0.7874 -0.4064)
			(end 0.7874 -0.4064)
			(stroke
				(width 0.1524)
				(type default)
			)
			(layer "F.SilkS")
		)
		(fp_line
			(start 0.7874 0.4064)
			(end -0.7874 0.4064)
			(stroke
				(width 0.1524)
				(type default)
			)
			(layer "F.SilkS")
		)
		(fp_line
			(start -0.7874 0.4064)
			(end -0.7874 -0.4064)
			(stroke
				(width 0.1524)
				(type default)
			)
			(layer "F.SilkS")
		)
		(fp_line
			(start -0.12065 -0.305054)
			(end -0.12065 -0.2794)
			(stroke
				(width 0.1)
				(type default)
			)
			(layer "F.Fab")
		)
		(fp_line
			(start -0.67945 -0.305054)
			(end -0.12065 -0.305054)
			(stroke
				(width 0.1)
				(type default)
			)
			(layer "F.Fab")
		)
		(fp_line
			(start 0.67945 -0.3048)
			(end 0.67945 0.3048)
			(stroke
				(width 0.1)
				(type default)
			)
			(layer "F.Fab")
		)
		(fp_line
			(start 0.12065 -0.3048)
			(end 0.67945 -0.3048)
			(stroke
				(width 0.1)
				(type default)
			)
			(layer "F.Fab")
		)
		(fp_line
			(start 0.12065 -0.2794)
			(end 0.12065 -0.3048)
			(stroke
				(width 0.1)
				(type default)
			)
			(layer "F.Fab")
		)
		(fp_line
			(start -0.12065 -0.2794)
			(end 0.12065 -0.2794)
			(stroke
				(width 0.1)
				(type default)
			)
			(layer "F.Fab")
		)
		(fp_line
			(start 0.120396 0.2794)
			(end -0.12065 0.2794)
			(stroke
				(width 0.1)
				(type default)
			)
			(layer "F.Fab")
		)
		(fp_line
			(start -0.12065 0.2794)
			(end -0.12065 0.3048)
			(stroke
				(width 0.1)
				(type default)
			)
			(layer "F.Fab")
		)
		(fp_line
			(start 0.67945 0.3048)
			(end 0.120396 0.3048)
			(stroke
				(width 0.1)
				(type default)
			)
			(layer "F.Fab")
		)
		(fp_line
			(start 0.120396 0.3048)
			(end 0.120396 0.2794)
			(stroke
				(width 0.1)
				(type default)
			)
			(layer "F.Fab")
		)
		(fp_line
			(start -0.12065 0.3048)
			(end -0.67945 0.3048)
			(stroke
				(width 0.1)
				(type default)
			)
			(layer "F.Fab")
		)
		(fp_line
			(start -0.67945 0.3048)
			(end -0.67945 -0.305054)
			(stroke
				(width 0.1)
				(type default)
			)
			(layer "F.Fab")
		)
		(pad "1" smd circle
			(at -0.40005 0 90)
			(size 0 0)
			(layers "F.Cu" "F.Mask" "F.Paste")
			(net "PWRGD_PCH_PWROK_R")
		)
		(pad "2" smd circle
			(at 0.40005 0 90)
			(size 0 0)
			(layers "F.Cu" "F.Mask" "F.Paste")
			(net "GND")
		)
	)
)
